# T6G (Grand Teton) — schematic netlist excerpt (pin names and nets, part order shuffled) for the footprints in the layout excerpt that follows; sources: Cadence DE-HDL packaged netlist, KiCad conversion of 04192023_DAF0TMB3IC0_F0TG_MB_C_brd_V02_OCP.brd

R635  Q_RES  51.1 1% EMPTY  pkg 0201LF  page 309 : A = CLK_100M_RETIMER_CPU0_P3_DN ; B = GND
C1336  Q_CAP  0.1UF 25V 10% X7R  pkg 0402  page 159 : A = P3V3_AUX ; B = GND
R340  Q_RES  49.9 1% EMPTY  pkg 0201LF  page 180 : A = USB2_CPU0_P0_DN ; B = GND

(kicad_pcb
	(version 20260206)
	(generator "pcbnew")
	(generator_version "10.0")
	(general
		(thickness 1.6)
		(legacy_teardrops no)
	)
	(paper "A4")
	(title_block
		(title "04192023_DAF0TMB3IC0_F0TG_MB_C_brd_V02_OCP.brd")
		(comment 1 "Grand Teton / footprints 303-305 of 8354")
	)
	(layers
		(0 "F.Cu" signal "TOP")
		(4 "In1.Cu" signal "GND")
		(6 "In2.Cu" signal "IN1")
		(8 "In3.Cu" signal "GND1")
		(10 "In4.Cu" signal "IN2")
		(12 "In5.Cu" signal "GND2")
		(14 "In6.Cu" signal "IN3")
		(16 "In7.Cu" signal "GND3")
		(18 "In8.Cu" signal "VCC")
		(20 "In9.Cu" signal "VCC1")
		(22 "In10.Cu" signal "GND4")
		(24 "In11.Cu" signal "IN4")
		(26 "In12.Cu" signal "GND5")
		(28 "In13.Cu" signal "IN5")
		(30 "In14.Cu" signal "GND6")
		(32 "In15.Cu" signal "IN6")
		(34 "In16.Cu" signal "GND7")
		(2 "B.Cu" signal "BOTTOM")
		(9 "F.Adhes" user "F.Adhesive")
		(11 "B.Adhes" user "B.Adhesive")
		(13 "F.Paste" user "Package Geometry/Pastemask Top")
		(15 "B.Paste" user "Package Geometry/Pastemask Bottom")
		(5 "F.SilkS" user "Ref Des/Silkscreen Top")
		(7 "B.SilkS" user "Ref Des/Silkscreen Bottom")
		(1 "F.Mask" user "Board Geometry/Soldermask Top")
		(3 "B.Mask" user "Board Geometry/Soldermask Bottom")
		(17 "Dwgs.User" user "User.Drawings")
		(19 "Cmts.User" user "User.Comments")
		(21 "Eco1.User" user "User.Eco1")
		(23 "Eco2.User" user "User.Eco2")
		(25 "Edge.Cuts" user "Board Geometry/Outline")
		(27 "Margin" user)
		(31 "F.CrtYd" user "Package Geometry/Place Bound Top")
		(29 "B.CrtYd" user "Package Geometry/Place Bound Bottom")
		(35 "F.Fab" user "Ref Des/Assembly Top")
		(33 "B.Fab" user "Ref Des/Assembly Bottom")
	)
	(footprint ""
		(layer "F.Cu")
		(at 301.419768 -145.877788 180)
		(property "Reference" "C1336"
			(at 0 0 180)
			(layer "F.SilkS")
			(hide yes)
			(effects
				(font
					(size 1.27 1.27)
				)
			)
		)
		(property "Value" ""
			(at 0 0 180)
			(layer "F.Fab")
			(effects
				(font
					(size 1.27 1.27)
				)
			)
		)
		(duplicate_pad_numbers_are_jumpers no)
		(fp_line
			(start 0.7874 0.4064)
			(end -0.7874 0.4064)
			(stroke
				(width 0.1524)
				(type default)
			)
			(layer "F.SilkS")
		)
		(fp_line
			(start 0.7874 -0.4064)
			(end 0.7874 0.4064)
			(stroke
				(width 0.1524)
				(type default)
			)
			(layer "F.SilkS")
		)
		(fp_line
			(start -0.7874 0.4064)
			(end -0.7874 -0.4064)
			(stroke
				(width 0.1524)
				(type default)
			)
			(layer "F.SilkS")
		)
		(fp_line
			(start -0.7874 -0.4064)
			(end 0.7874 -0.4064)
			(stroke
				(width 0.1524)
				(type default)
			)
			(layer "F.SilkS")
		)
		(fp_line
			(start 0.67945 0.3048)
			(end 0.120396 0.3048)
			(stroke
				(width 0.1)
				(type default)
			)
			(layer "F.Fab")
		)
		(fp_line
			(start 0.67945 -0.3048)
			(end 0.67945 0.3048)
			(stroke
				(width 0.1)
				(type default)
			)
			(layer "F.Fab")
		)
		(fp_line
			(start 0.12065 -0.2794)
			(end 0.12065 -0.3048)
			(stroke
				(width 0.1)
				(type default)
			)
			(layer "F.Fab")
		)
		(fp_line
			(start 0.12065 -0.3048)
			(end 0.67945 -0.3048)
			(stroke
				(width 0.1)
				(type default)
			)
			(layer "F.Fab")
		)
		(fp_line
			(start 0.120396 0.3048)
			(end 0.120396 0.2794)
			(stroke
				(width 0.1)
				(type default)
			)
			(layer "F.Fab")
		)
		(fp_line
			(start 0.120396 0.2794)
			(end -0.12065 0.2794)
			(stroke
				(width 0.1)
				(type default)
			)
			(layer "F.Fab")
		)
		(fp_line
			(start -0.12065 0.3048)
			(end -0.67945 0.3048)
			(stroke
				(width 0.1)
				(type default)
			)
			(layer "F.Fab")
		)
		(fp_line
			(start -0.12065 0.2794)
			(end -0.12065 0.3048)
			(stroke
				(width 0.1)
				(type default)
			)
			(layer "F.Fab")
		)
		(fp_line
			(start -0.12065 -0.2794)
			(end 0.12065 -0.2794)
			(stroke
				(width 0.1)
				(type default)
			)
			(layer "F.Fab")
		)
		(fp_line
			(start -0.12065 -0.305054)
			(end -0.12065 -0.2794)
			(stroke
				(width 0.1)
				(type default)
			)
			(layer "F.Fab")
		)
		(fp_line
			(start -0.67945 0.3048)
			(end -0.67945 -0.305054)
			(stroke
				(width 0.1)
				(type default)
			)
			(layer "F.Fab")
		)
		(fp_line
			(start -0.67945 -0.305054)
			(end -0.12065 -0.305054)
			(stroke
				(width 0.1)
				(type default)
			)
			(layer "F.Fab")
		)
		(pad "1" smd circle
			(at -0.40005 0 180)
			(size 0 0)
			(layers "F.Cu" "F.Mask" "F.Paste")
			(net "P3V3_AUX")
		)
		(pad "2" smd circle
			(at 0.40005 0 180)
			(size 0 0)
			(layers "F.Cu" "F.Mask" "F.Paste")
			(net "GND")
		)
	)
	(footprint ""
		(layer "F.Cu")
		(at 131.90728 -27.25928)
		(property "Reference" "R340"
			(at 0 0 0)
			(layer "F.SilkS")
			(hide yes)
			(effects
				(font
					(size 1.27 1.27)
				)
			)
		)
		(property "Value" ""
			(at 0 0 0)
			(layer "F.Fab")
			(effects
				(font
					(size 1.27 1.27)
				)
			)
		)
		(duplicate_pad_numbers_are_jumpers no)
		(fp_line
			(start -0.32512 -0.175006)
			(end 0.32512 -0.175006)
			(stroke
				(width 0.1)
				(type default)
			)
			(layer "F.Fab")
		)
		(fp_line
			(start -0.32512 0.175006)
			(end -0.32512 -0.175006)
			(stroke
				(width 0.1)
				(type default)
			)
			(layer "F.Fab")
		)
		(fp_line
			(start 0.32512 -0.175006)
			(end 0.32512 0.175006)
			(stroke
				(width 0.1)
				(type default)
			)
			(layer "F.Fab")
		)
		(fp_line
			(start 0.32512 0.175006)
			(end -0.32512 0.175006)
			(stroke
				(width 0.1)
				(type default)
			)
			(layer "F.Fab")
		)
		(pad "1" smd rect
			(at -0.2667 0)
			(size 0.3048 0.381)
			(layers "F.Cu" "F.Mask" "F.Paste")
			(net "USB2_CPU0_P0_DN")
		)
		(pad "2" smd rect
			(at 0.2667 0 180)
			(size 0.3048 0.381)
			(layers "F.Cu" "F.Mask" "F.Paste")
			(net "GND")
		)
	)
	(footprint ""
		(layer "F.Cu")
		(at 366.64392 -395.066774 -90)
		(property "Reference" "R635"
			(at 0 0 270)
			(layer "F.SilkS")
			(hide yes)
			(effects
				(font
					(size 1.27 1.27)
				)
			)
		)
		(property "Value" ""
			(at 0 0 270)
			(layer "F.Fab")
			(effects
				(font
					(size 1.27 1.27)
				)
			)
		)
		(duplicate_pad_numbers_are_jumpers no)
		(fp_line
			(start -0.32512 0.175006)
			(end -0.32512 -0.175006)
			(stroke
				(width 0.1)
				(type default)
			)
			(layer "F.Fab")
		)
		(fp_line
			(start 0.32512 0.175006)
			(end -0.32512 0.175006)
			(stroke
				(width 0.1)
				(type default)
			)
			(layer "F.Fab")
		)
		(fp_line
			(start -0.32512 -0.175006)
			(end 0.32512 -0.175006)
			(stroke
				(width 0.1)
				(type default)
			)
			(layer "F.Fab")
		)
		(fp_line
			(start 0.32512 -0.175006)
			(end 0.32512 0.175006)
			(stroke
				(width 0.1)
				(type default)
			)
			(layer "F.Fab")
		)
		(pad "1" smd rect
			(at -0.2667 0 270)
			(size 0.3048 0.381)
			(layers "F.Cu" "F.Mask" "F.Paste")
			(net "CLK_100M_RETIMER_CPU0_P3_DN")
		)
		(pad "2" smd rect
			(at 0.2667 0 90)
			(size 0.3048 0.381)
			(layers "F.Cu" "F.Mask" "F.Paste")
			(net "GND")
		)
	)
)
